# BASEBOARD_FAB2 (Tioga Pass) — schematic netlist excerpt (pin names and nets, part order shuffled) for the footprints in the layout excerpt that follows; sources: Cadence DE-HDL packaged netlist, KiCad conversion of Wiwynn_Tioga_Pass_MB.brd

T1P23  TPAD-DIFF-4P-GP  pkg DISCRET-GB3  page 256
  \1\  = L12_100OHM_6INCH_DP
  \2\  = L12_100OHM_6INCH_DN
  GND1  = GND
  GND2  = GND

R25W62  RES  100.0K 1% CHIP  pkg 0402  page 145 : A = RST_PLTRST_BUF_N_R ; B = GND

(kicad_pcb
	(version 20260206)
	(generator "pcbnew")
	(generator_version "10.0")
	(general
		(thickness 1.6)
		(legacy_teardrops no)
	)
	(paper "A4")
	(title_block
		(title "Wiwynn_Tioga_Pass_MB.brd")
		(comment 1 "Tioga Pass / footprints 444-445 of 4770")
	)
	(layers
		(0 "F.Cu" signal "TOP")
		(4 "In1.Cu" signal "L2GND")
		(6 "In2.Cu" signal "L3")
		(8 "In3.Cu" signal "L4GND")
		(10 "In4.Cu" signal "L5")
		(12 "In5.Cu" signal "L6GND")
		(14 "In6.Cu" signal "L7VCC")
		(16 "In7.Cu" signal "L8VCC")
		(18 "In8.Cu" signal "L9GND")
		(20 "In9.Cu" signal "L10")
		(22 "In10.Cu" signal "L11GND")
		(24 "In11.Cu" signal "L12")
		(26 "In12.Cu" signal "L13GND")
		(2 "B.Cu" signal "BOTTOM")
		(9 "F.Adhes" user "F.Adhesive")
		(11 "B.Adhes" user "B.Adhesive")
		(13 "F.Paste" user "Package Geometry/Pastemask Top")
		(15 "B.Paste" user "Package Geometry/Pastemask Bottom")
		(5 "F.SilkS" user "Ref Des/Silkscreen Top")
		(7 "B.SilkS" user "Ref Des/Silkscreen Bottom")
		(1 "F.Mask" user "Board Geometry/Soldermask Top")
		(3 "B.Mask" user "Board Geometry/Soldermask Bottom")
		(17 "Dwgs.User" user "User.Drawings")
		(19 "Cmts.User" user "User.Comments")
		(21 "Eco1.User" user "User.Eco1")
		(23 "Eco2.User" user "User.Eco2")
		(25 "Edge.Cuts" user "Board Geometry/Outline")
		(27 "Margin" user)
		(31 "F.CrtYd" user "Package Geometry/Place Bound Top")
		(29 "B.CrtYd" user "Package Geometry/Place Bound Bottom")
		(35 "F.Fab" user "Ref Des/Assembly Top")
		(33 "B.Fab" user "Ref Des/Assembly Bottom")
	)
	(footprint ""
		(layer "F.Cu")
		(at 412.3944 -50.18532 90)
		(property "Reference" "R25W62"
			(at -0.8382 -0.67818 90)
			(unlocked yes)
			(layer "F.SilkS")
			(effects
				(font
					(size 0.4064 0.254)
					(thickness 0.1524)
				)
				(justify left)
			)
		)
		(property "Value" ""
			(at 0 0 90)
			(layer "F.Fab")
			(effects
				(font
					(size 1.27 1.27)
				)
			)
		)
		(duplicate_pad_numbers_are_jumpers no)
		(fp_poly
			(pts
				(xy -0.2794 -0.1016) (xy 0.2794 -0.1016) (xy 0.2794 0.9906) (xy -0.2794 0.9906)
			)
			(stroke
				(width 0)
				(type default)
			)
			(fill no)
			(layer "F.CrtYd")
		)
		(fp_line
			(start 0.2794 -0.1016)
			(end -0.2794 -0.1016)
			(stroke
				(width 0.1)
				(type default)
			)
			(layer "F.Fab")
		)
		(fp_line
			(start -0.2794 -0.1016)
			(end -0.2794 0.9906)
			(stroke
				(width 0.1)
				(type default)
			)
			(layer "F.Fab")
		)
		(fp_line
			(start 0.2794 0.9906)
			(end 0.2794 -0.1016)
			(stroke
				(width 0.1)
				(type default)
			)
			(layer "F.Fab")
		)
		(fp_line
			(start -0.2794 0.9906)
			(end 0.2794 0.9906)
			(stroke
				(width 0.1)
				(type default)
			)
			(layer "F.Fab")
		)
		(pad "1" smd rect
			(at 0 0 90)
			(size 0.508 0.508)
			(layers "F.Cu" "F.Mask" "F.Paste")
			(net "RST_PLTRST_BUF_N_R")
		)
		(pad "2" smd rect
			(at 0 0.889 90)
			(size 0.508 0.508)
			(layers "F.Cu" "F.Mask" "F.Paste")
			(net "GND")
		)
		(zone
			(layer "F.Cu")
			(hatch none 0.5)
			(connect_pads
				(clearance 0)
			)
			(min_thickness 0.25)
			(keepout
				(tracks allowed)
				(vias not_allowed)
				(pads allowed)
				(copperpour not_allowed)
				(footprints allowed)
			)
			(placement
				(enabled no)
				(sheetname "")
			)
			(fill
				(thermal_gap 0.5)
				(thermal_bridge_width 0.5)
				(island_removal_mode 0)
			)
			(polygon
				(pts
					(xy 412.6484 -49.93132) (xy 412.6484 -50.43932) (xy 413.0294 -50.43932) (xy 413.0294 -49.93132)
				)
			)
		)
		(zone
			(layer "F.Cu")
			(hatch none 0.5)
			(connect_pads
				(clearance 0)
			)
			(min_thickness 0.25)
			(keepout
				(tracks not_allowed)
				(vias allowed)
				(pads allowed)
				(copperpour not_allowed)
				(footprints allowed)
			)
			(placement
				(enabled no)
				(sheetname "")
			)
			(fill
				(thermal_gap 0.5)
				(thermal_bridge_width 0.5)
				(island_removal_mode 0)
			)
			(polygon
				(pts
					(xy 413.0294 -49.93132) (xy 413.0294 -50.43932) (xy 412.6484 -50.43932) (xy 412.6484 -49.93132)
				)
			)
		)
	)
	(footprint ""
		(layer "F.Cu")
		(at 362.523532 12.003278 -90)
		(property "Reference" "T1P23"
			(at 0 0 270)
			(layer "F.SilkS")
			(hide yes)
			(effects
				(font
					(size 1.27 1.27)
				)
			)
		)
		(property "Value" "*"
			(at -3.302 1.12395 270)
			(unlocked yes)
			(layer "F.Fab")
			(hide yes)
			(effects
				(font
					(size 0.889 0.889)
					(thickness 0.1524)
				)
			)
		)
		(property "Device Type" "TPAD-DIFF-4P-GP_DISCRET-GB3-TPA"
			(at -3.302 -0.40005 270)
			(unlocked yes)
			(layer "F.Fab")
			(hide yes)
			(effects
				(font
					(size 0.889 0.889)
					(thickness 0.1524)
				)
			)
		)
		(duplicate_pad_numbers_are_jumpers no)
		(fp_line
			(start -2.286 2.286)
			(end 2.286 2.286)
			(stroke
				(width 0.1524)
				(type default)
			)
			(layer "F.SilkS")
		)
		(fp_line
			(start 2.286 2.286)
			(end 2.286 -2.286)
			(stroke
				(width 0.1524)
				(type default)
			)
			(layer "F.SilkS")
		)
		(fp_line
			(start -2.286 -2.286)
			(end -2.286 2.286)
			(stroke
				(width 0.1524)
				(type default)
			)
			(layer "F.SilkS")
		)
		(fp_line
			(start 2.286 -2.286)
			(end -2.286 -2.286)
			(stroke
				(width 0.1524)
				(type default)
			)
			(layer "F.SilkS")
		)
		(fp_line
			(start -2.413 -2.413)
			(end -2.413 -1.143)
			(stroke
				(width 0.4064)
				(type default)
			)
			(layer "F.SilkS")
		)
		(fp_line
			(start -1.143 -2.413)
			(end -2.413 -2.413)
			(stroke
				(width 0.4064)
				(type default)
			)
			(layer "F.SilkS")
		)
		(fp_rect
			(start -2.54 2.54)
			(end 2.54 -2.54)
			(stroke
				(width 0)
				(type default)
			)
			(fill no)
			(layer "F.CrtYd")
		)
		(fp_rect
			(start -2.54 2.54)
			(end 2.54 -2.54)
			(stroke
				(width 0)
				(type default)
			)
			(fill no)
			(layer "F.Fab")
		)
		(pad "1" thru_hole circle
			(at -1.27 -1.27 270)
			(size 1.524 1.524)
			(drill 0.9144)
			(layers "*.Cu" "*.Mask")
			(remove_unused_layers no)
			(net "L12_100OHM_6INCH_DP")
			(clearance -0.0508)
			(thermal_gap 0.127)
			(padstack
				(mode front_inner_back)
				(layer "Inner"
					(shape circle)
					(size 1.1684 1.1684)
					(clearance 0.127)
				)
				(layer "B.Cu"
					(shape circle)
					(size 1.524 1.524)
					(clearance -0.0508)
				)
			)
		)
		(pad "2" thru_hole circle
			(at 1.27 -1.27 270)
			(size 1.524 1.524)
			(drill 0.9144)
			(layers "*.Cu" "*.Mask")
			(remove_unused_layers no)
			(net "L12_100OHM_6INCH_DN")
			(clearance -0.0508)
			(thermal_gap 0.127)
			(padstack
				(mode front_inner_back)
				(layer "Inner"
					(shape circle)
					(size 1.1684 1.1684)
					(clearance 0.127)
				)
				(layer "B.Cu"
					(shape circle)
					(size 1.524 1.524)
					(clearance -0.0508)
				)
			)
		)
		(pad "GND1" thru_hole rect
			(at -1.27 1.27 270)
			(size 1.524 1.524)
			(drill 0.9144)
			(layers "*.Cu" "*.Mask")
			(remove_unused_layers no)
			(net "GND")
			(clearance -0.0508)
			(thermal_gap 0.127)
			(padstack
				(mode front_inner_back)
				(layer "Inner"
					(shape circle)
					(size 1.1684 1.1684)
					(clearance 0.127)
				)
				(layer "B.Cu"
					(shape rect)
					(size 1.524 1.524)
					(clearance -0.0508)
				)
			)
		)
		(pad "GND2" thru_hole rect
			(at 1.27 1.27 270)
			(size 1.524 1.524)
			(drill 0.9144)
			(layers "*.Cu" "*.Mask")
			(remove_unused_layers no)
			(net "GND")
			(clearance -0.0508)
			(thermal_gap 0.127)
			(padstack
				(mode front_inner_back)
				(layer "Inner"
					(shape circle)
					(size 1.1684 1.1684)
					(clearance 0.127)
				)
				(layer "B.Cu"
					(shape rect)
					(size 1.524 1.524)
					(clearance -0.0508)
				)
			)
		)
	)
)
